(kicad_pcb
	(version 20241229)
	(generator "pcbnew")
	(generator_version "9.0")
	(general
		(thickness 1.599998)
		(legacy_teardrops no)
	)
	(paper "A4")
	(title_block
		(title "Artix - Datacenter Secure Control Module (DC-SCM)")
		(date "2024-11-06")
		(rev "1.1.3")
		(comment 9 "footprints 104-106 of 544")
	)
	(layers
		(0 "F.Cu" signal)
		(4 "In1.Cu" signal)
		(6 "In2.Cu" signal)
		(8 "In3.Cu" signal)
		(10 "In4.Cu" signal)
		(12 "In5.Cu" signal)
		(14 "In6.Cu" signal)
		(2 "B.Cu" signal)
		(9 "F.Adhes" user "F.Adhesive")
		(11 "B.Adhes" user "B.Adhesive")
		(13 "F.Paste" user)
		(15 "B.Paste" user)
		(5 "F.SilkS" user "F.Silkscreen")
		(7 "B.SilkS" user "B.Silkscreen")
		(1 "F.Mask" user)
		(3 "B.Mask" user)
		(17 "Dwgs.User" user "User.Drawings")
		(19 "Cmts.User" user "User.Comments")
		(21 "Eco1.User" user "User.Eco1")
		(23 "Eco2.User" user "User.Eco2")
		(25 "Edge.Cuts" user)
		(27 "Margin" user)
		(31 "F.CrtYd" user "F.Courtyard")
		(29 "B.CrtYd" user "B.Courtyard")
		(35 "F.Fab" user)
		(33 "B.Fab" user)
	)
	(footprint "antmicro-footprints:QFN-32-1EP_5x5mm"
		(layer "F.Cu")
		(at 124.995 127.525 180)
		(property "Reference" "U18"
			(at -0.905 3.125 180)
			(layer "F.SilkS")
			(effects
				(font
					(size 0.7 0.7)
					(thickness 0.15)
				)
				(justify left bottom)
			)
		)
		(property "Value" "USB3300-EZK-TR"
			(at -4.94 3.91 180)
			(layer "F.Fab")
			(effects
				(font
					(size 0.7 0.7)
					(thickness 0.15)
				)
				(justify left bottom)
			)
		)
		(property "Datasheet" "https://ww1.microchip.com/downloads/en/DeviceDoc/00001783C.pdf"
			(at 0 0 180)
			(layer "F.Fab")
			(hide yes)
			(effects
				(font
					(size 1.27 1.27)
					(thickness 0.15)
				)
			)
		)
		(property "Description" "USB Interface, USB Host Controller, USB 2.0 OTG, 3 V, 3.6 V, VQFN, 32 Pins"
			(at 0 0 180)
			(layer "F.Fab")
			(hide yes)
			(effects
				(font
					(size 1.27 1.27)
					(thickness 0.15)
				)
			)
		)
		(property "Author" "Antmicro"
			(at 249.99 255.05 0)
			(layer "F.Fab")
			(hide yes)
			(effects
				(font
					(size 1 1)
					(thickness 0.15)
				)
			)
		)
		(property "License" "Apache-2.0"
			(at 249.99 255.05 0)
			(layer "F.Fab")
			(hide yes)
			(effects
				(font
					(size 1 1)
					(thickness 0.15)
				)
			)
		)
		(property "MPN" "USB3300-EZK-TR"
			(at 249.99 255.05 0)
			(layer "F.Fab")
			(hide yes)
			(effects
				(font
					(size 1 1)
					(thickness 0.15)
				)
			)
		)
		(property "Manufacturer" "Microchip Technology"
			(at 249.99 255.05 0)
			(layer "F.Fab")
			(hide yes)
			(effects
				(font
					(size 1 1)
					(thickness 0.15)
				)
			)
		)
		(sheetname "/Interfaces/")
		(sheetfile "interfaces.kicad_sch")
		(attr smd)
		(fp_line
			(start 2.581 2.648)
			(end 2.178 2.648)
			(stroke
				(width 0.15)
				(type solid)
			)
			(layer "F.SilkS")
		)
		(fp_line
			(start 2.581 2.249)
			(end 2.581 2.648)
			(stroke
				(width 0.15)
				(type solid)
			)
			(layer "F.SilkS")
		)
		(fp_line
			(start 2.581 -2.551)
			(end 2.581 -2.149)
			(stroke
				(width 0.15)
				(type solid)
			)
			(layer "F.SilkS")
		)
		(fp_line
			(start 2.581 -2.551)
			(end 2.178 -2.551)
			(stroke
				(width 0.15)
				(type solid)
			)
			(layer "F.SilkS")
		)
		(fp_line
			(start -2.221 2.648)
			(end -2.62 2.648)
			(stroke
				(width 0.15)
				(type solid)
			)
			(layer "F.SilkS")
		)
		(fp_line
			(start -2.221 -2.551)
			(end -2.62 -2.149)
			(stroke
				(width 0.15)
				(type solid)
			)
			(layer "F.SilkS")
		)
		(fp_line
			(start -2.62 2.648)
			(end -2.62 2.249)
			(stroke
				(width 0.15)
				(type solid)
			)
			(layer "F.SilkS")
		)
		(fp_circle
			(center -3.25 -1.702)
			(end -3.2 -1.702)
			(stroke
				(width 0.15)
				(type solid)
			)
			(fill yes)
			(layer "F.SilkS")
		)
		(fp_rect
			(start 0.203 1.474)
			(end 1.403 0.274)
			(stroke
				(width 0.2)
				(type solid)
			)
			(fill yes)
			(layer "F.Paste")
		)
		(fp_rect
			(start 0.203 -0.175)
			(end 1.403 -1.375)
			(stroke
				(width 0.2)
				(type solid)
			)
			(fill yes)
			(layer "F.Paste")
		)
		(fp_rect
			(start -1.446 1.474)
			(end -0.246 0.274)
			(stroke
				(width 0.2)
				(type solid)
			)
			(fill yes)
			(layer "F.Paste")
		)
		(fp_rect
			(start -1.446 -0.175)
			(end -0.246 -1.375)
			(stroke
				(width 0.2)
				(type solid)
			)
			(fill yes)
			(layer "F.Paste")
		)
		(fp_rect
			(start -2.74 -2.75)
			(end 2.75 2.74)
			(stroke
				(width 0.05)
				(type solid)
			)
			(fill no)
			(layer "F.CrtYd")
		)
		(fp_line
			(start -2.499 -2.299)
			(end -2.298 -2.5)
			(stroke
				(width 0.15)
				(type solid)
			)
			(layer "F.Fab")
		)
		(fp_rect
			(start -2.499 -2.5)
			(end 2.5 2.499)
			(stroke
				(width 0.15)
				(type solid)
			)
			(fill no)
			(layer "F.Fab")
		)
		(pad "1" smd rect
			(at -2.495 -1.702 90)
			(size 0.28 0.85)
			(layers "F.Cu" "F.Mask" "F.Paste")
			(net 1 "GND")
			(pinfunction "GND")
			(pintype "power_in")
			(solder_mask_margin 0.07)
		)
		(pad "2" smd rect
			(at -2.495 -1.2 90)
			(size 0.28 0.85)
			(layers "F.Cu" "F.Mask" "F.Paste")
			(net 1 "GND")
			(pinfunction "GND")
			(pintype "passive")
			(solder_mask_margin 0.07)
		)
		(pad "3" smd rect
			(at -2.495 -0.701 90)
			(size 0.28 0.85)
			(layers "F.Cu" "F.Mask" "F.Paste")
			(net 652 "unconnected-(U18-CPEN-Pad3)")
			(pinfunction "CPEN")
			(pintype "output+no_connect")
			(solder_mask_margin 0.07)
		)
		(pad "4" smd rect
			(at -2.495 -0.201 90)
			(size 0.28 0.85)
			(layers "F.Cu" "F.Mask" "F.Paste")
			(net 304 "Net-(U18-VBUS)")
			(pinfunction "VBUS")
			(pintype "bidirectional")
			(solder_mask_margin 0.07)
		)
		(pad "5" smd rect
			(at -2.495 0.296 90)
			(size 0.28 0.85)
			(layers "F.Cu" "F.Mask" "F.Paste")
			(net 653 "unconnected-(U18-ID-Pad5)")
			(pinfunction "ID")
			(pintype "input+no_connect")
			(solder_mask_margin 0.07)
		)
		(pad "6" smd rect
			(at -2.495 0.8 90)
			(size 0.28 0.85)
			(layers "F.Cu" "F.Mask" "F.Paste")
			(net 2 "VCC3V3")
			(pinfunction "VDD3.3")
			(pintype "power_in")
			(solder_mask_margin 0.07)
		)
		(pad "7" smd rect
			(at -2.495 1.3 90)
			(size 0.28 0.85)
			(layers "F.Cu" "F.Mask" "F.Paste")
			(net 383 "USB2_D_P")
			(pinfunction "DP")
			(pintype "bidirectional")
			(solder_mask_margin 0.07)
		)
		(pad "8" smd rect
			(at -2.495 1.8 90)
			(size 0.28 0.85)
			(layers "F.Cu" "F.Mask" "F.Paste")
			(net 384 "USB2_D_N")
			(pinfunction "DM")
			(pintype "bidirectional")
			(solder_mask_margin 0.07)
		)
		(pad "9" smd rect
			(at -1.768 2.523 90)
			(size 0.85 0.28)
			(layers "F.Cu" "F.Mask" "F.Paste")
			(net 457 "ULPI2_RESET")
			(pinfunction "RESET")
			(pintype "input")
			(solder_mask_margin 0.07)
		)
		(pad "10" smd rect
			(at -1.269 2.523 90)
			(size 0.85 0.28)
			(layers "F.Cu" "F.Mask" "F.Paste")
			(net 654 "unconnected-(U18-EXTVBUS-Pad10)")
			(pinfunction "EXTVBUS")
			(pintype "input+no_connect")
			(solder_mask_margin 0.07)
		)
		(pad "11" smd rect
			(at -0.772 2.523 90)
			(size 0.85 0.28)
			(layers "F.Cu" "F.Mask" "F.Paste")
			(net 458 "ULPI2_NXT")
			(pinfunction "NXT")
			(pintype "output")
			(solder_mask_margin 0.07)
		)
		(pad "12" smd rect
			(at -0.272 2.523 90)
			(size 0.85 0.28)
			(layers "F.Cu" "F.Mask" "F.Paste")
			(net 459 "ULPI2_DIR")
			(pinfunction "DIR")
			(pintype "output")
			(solder_mask_margin 0.07)
		)
		(pad "13" smd rect
			(at 0.229 2.523 90)
			(size 0.85 0.28)
			(layers "F.Cu" "F.Mask" "F.Paste")
			(net 460 "ULPI2_STP")
			(pinfunction "STP")
			(pintype "input")
			(solder_mask_margin 0.07)
		)
		(pad "14" smd rect
			(at 0.728 2.523 90)
			(size 0.85 0.28)
			(layers "F.Cu" "F.Mask" "F.Paste")
			(net 461 "ULPI2_CLKOUT")
			(pinfunction "CLKOUT")
			(pintype "output")
			(solder_mask_margin 0.07)
		)
		(pad "15" smd rect
			(at 1.23 2.523 90)
			(size 0.85 0.28)
			(layers "F.Cu" "F.Mask" "F.Paste")
			(net 108 "Net-(C177-Pad2)")
			(pinfunction "VDD1.8")
			(pintype "power_in")
			(solder_mask_margin 0.07)
		)
		(pad "16" smd rect
			(at 1.73 2.523 90)
			(size 0.85 0.28)
			(layers "F.Cu" "F.Mask" "F.Paste")
			(net 2 "VCC3V3")
			(pinfunction "VDD3.3")
			(pintype "passive")
			(solder_mask_margin 0.07)
		)
		(pad "17" smd rect
			(at 2.456 1.8 90)
			(size 0.28 0.85)
			(layers "F.Cu" "F.Mask" "F.Paste")
			(net 462 "ULPI2_DATA7")
			(pinfunction "DATA[7]")
			(pintype "bidirectional")
			(solder_mask_margin 0.07)
		)
		(pad "18" smd rect
			(at 2.456 1.3 90)
			(size 0.28 0.85)
			(layers "F.Cu" "F.Mask" "F.Paste")
			(net 463 "ULPI2_DATA6")
			(pinfunction "DATA[6]")
			(pintype "bidirectional")
			(solder_mask_margin 0.07)
		)
		(pad "19" smd rect
			(at 2.456 0.8 90)
			(size 0.28 0.85)
			(layers "F.Cu" "F.Mask" "F.Paste")
			(net 464 "ULPI2_DATA5")
			(pinfunction "DATA[5]")
			(pintype "bidirectional")
			(solder_mask_margin 0.07)
		)
		(pad "20" smd rect
			(at 2.456 0.296 90)
			(size 0.28 0.85)
			(layers "F.Cu" "F.Mask" "F.Paste")
			(net 465 "ULPI2_DATA4")
			(pinfunction "DATA[4]")
			(pintype "bidirectional")
			(solder_mask_margin 0.07)
		)
		(pad "21" smd rect
			(at 2.456 -0.201 90)
			(size 0.28 0.85)
			(layers "F.Cu" "F.Mask" "F.Paste")
			(net 466 "ULPI2_DATA3")
			(pinfunction "DATA[3]")
			(pintype "bidirectional")
			(solder_mask_margin 0.07)
		)
		(pad "22" smd rect
			(at 2.456 -0.701 90)
			(size 0.28 0.85)
			(layers "F.Cu" "F.Mask" "F.Paste")
			(net 467 "ULPI2_DATA2")
			(pinfunction "DATA[2]")
			(pintype "bidirectional")
			(solder_mask_margin 0.07)
		)
		(pad "23" smd rect
			(at 2.456 -1.2 90)
			(size 0.28 0.85)
			(layers "F.Cu" "F.Mask" "F.Paste")
			(net 468 "ULPI2_DATA1")
			(pinfunction "DATA[1]")
			(pintype "bidirectional")
			(solder_mask_margin 0.07)
		)
		(pad "24" smd rect
			(at 2.456 -1.702 90)
			(size 0.28 0.85)
			(layers "F.Cu" "F.Mask" "F.Paste")
			(net 469 "ULPI2_DATA0")
			(pinfunction "DATA[0]")
			(pintype "bidirectional")
			(solder_mask_margin 0.07)
		)
		(pad "25" smd rect
			(at 1.73 -2.426 90)
			(size 0.85 0.28)
			(layers "F.Cu" "F.Mask" "F.Paste")
			(net 2 "VCC3V3")
			(pinfunction "VDD3.3")
			(pintype "passive")
			(solder_mask_margin 0.07)
		)
		(pad "26" smd rect
			(at 1.23 -2.426 90)
			(size 0.85 0.28)
			(layers "F.Cu" "F.Mask" "F.Paste")
			(net 108 "Net-(C177-Pad2)")
			(pinfunction "VDD1.8")
			(pintype "passive")
			(solder_mask_margin 0.07)
		)
		(pad "27" smd rect
			(at 0.728 -2.426 90)
			(size 0.85 0.28)
			(layers "F.Cu" "F.Mask" "F.Paste")
			(net 655 "unconnected-(U18-XO-Pad27)")
			(pinfunction "XO")
			(pintype "output+no_connect")
			(solder_mask_margin 0.07)
		)
		(pad "28" smd rect
			(at 0.229 -2.426 90)
			(size 0.85 0.28)
			(layers "F.Cu" "F.Mask" "F.Paste")
			(net 656 "Net-(U18-XI)")
			(pinfunction "XI")
			(pintype "input")
			(solder_mask_margin 0.07)
		)
		(pad "29" smd rect
			(at -0.272 -2.426 90)
			(size 0.85 0.28)
			(layers "F.Cu" "F.Mask" "F.Paste")
			(net 11 "Net-(U18-VDDA1.8)")
			(pinfunction "VDDA1.8")
			(pintype "power_in")
			(solder_mask_margin 0.07)
		)
		(pad "30" smd rect
			(at -0.772 -2.426 90)
			(size 0.85 0.28)
			(layers "F.Cu" "F.Mask" "F.Paste")
			(net 2 "VCC3V3")
			(pinfunction "VDD3.3")
			(pintype "passive")
			(solder_mask_margin 0.07)
		)
		(pad "31" smd rect
			(at -1.269 -2.426 90)
			(size 0.85 0.28)
			(layers "F.Cu" "F.Mask" "F.Paste")
			(net 310 "Net-(U18-REG_EN)")
			(pinfunction "REG_EN")
			(pintype "bidirectional")
			(solder_mask_margin 0.07)
		)
		(pad "32" smd rect
			(at -1.768 -2.426 90)
			(size 0.85 0.28)
			(layers "F.Cu" "F.Mask" "F.Paste")
			(net 303 "Net-(U18-RBIAS)")
			(pinfunction "RBIAS")
			(pintype "bidirectional")
			(solder_mask_margin 0.07)
		)
		(pad "33" smd rect
			(at -0.02 0.048 90)
			(size 3.45 3.45)
			(layers "F.Cu" "F.Mask")
			(net 1 "GND")
			(pinfunction "EP")
			(pintype "passive")
		)
	)
	(footprint "antmicro-footprints:C_0402_1005Metric"
		(layer "F.Cu")
		(at 103.374 140.075 -90)
		(descr "Capacitor SMD 0402")
		(tags "capacitor SMD 0402")
		(property "Reference" "C8"
			(at -2.275 -0.326 90)
			(layer "F.SilkS")
			(effects
				(font
					(size 0.7 0.7)
					(thickness 0.15)
				)
				(justify right bottom)
			)
		)
		(property "Value" "C_470n_0402"
			(at 0 1.4 90)
			(layer "F.Fab")
			(effects
				(font
					(size 0.7 0.7)
					(thickness 0.15)
				)
				(justify right bottom)
			)
		)
		(property "Datasheet" "https://product.tdk.com/en/search/capacitor/ceramic/mlcc/info?part_no=C1005X5R1E474M050BB"
			(at 0 0 270)
			(layer "F.Fab")
			(hide yes)
			(effects
				(font
					(size 1.27 1.27)
					(thickness 0.15)
				)
			)
		)
		(property "Description" "SMD Multilayer Ceramic Capacitor, 0.47 µF, 25 V, 0402 [1005 Metric], ± 20%, X5R, C"
			(at 0 0 270)
			(layer "F.Fab")
			(hide yes)
			(effects
				(font
					(size 1.27 1.27)
					(thickness 0.15)
				)
			)
		)
		(property "Author" "Antmicro"
			(at -36.701 243.449 0)
			(layer "F.Fab")
			(hide yes)
			(effects
				(font
					(size 1 1)
					(thickness 0.15)
				)
			)
		)
		(property "Dielectric" ""
			(at -36.701 243.449 0)
			(layer "F.Fab")
			(hide yes)
			(effects
				(font
					(size 1 1)
					(thickness 0.15)
				)
			)
		)
		(property "License" "Apache-2.0"
			(at -36.701 243.449 0)
			(layer "F.Fab")
			(hide yes)
			(effects
				(font
					(size 1 1)
					(thickness 0.15)
				)
			)
		)
		(property "MPN" "C1005X5R1E474M050BB"
			(at -36.701 243.449 0)
			(layer "F.Fab")
			(hide yes)
			(effects
				(font
					(size 1 1)
					(thickness 0.15)
				)
			)
		)
		(property "Manufacturer" "TDK"
			(at -36.701 243.449 0)
			(layer "F.Fab")
			(hide yes)
			(effects
				(font
					(size 1 1)
					(thickness 0.15)
				)
			)
		)
		(property "Val" "470n"
			(at -36.701 243.449 0)
			(layer "F.Fab")
			(hide yes)
			(effects
				(font
					(size 1 1)
					(thickness 0.15)
				)
			)
		)
		(property "Voltage" ""
			(at -36.701 243.449 0)
			(layer "F.Fab")
			(hide yes)
			(effects
				(font
					(size 1 1)
					(thickness 0.15)
				)
			)
		)
		(sheetname "/DDR3/")
		(sheetfile "ddr3.kicad_sch")
		(attr smd)
		(fp_rect
			(start -0.925 -0.47)
			(end 0.925 0.47)
			(stroke
				(width 0.05)
				(type default)
			)
			(fill no)
			(layer "F.CrtYd")
		)
		(fp_line
			(start -0.494 0.248)
			(end -0.494 -0.25)
			(stroke
				(width 0.15)
				(type solid)
			)
			(layer "F.Fab")
		)
		(fp_line
			(start 0.504 0.248)
			(end -0.494 0.248)
			(stroke
				(width 0.15)
				(type solid)
			)
			(layer "F.Fab")
		)
		(fp_line
			(start -0.494 -0.25)
			(end 0.504 -0.25)
			(stroke
				(width 0.15)
				(type solid)
			)
			(layer "F.Fab")
		)
		(fp_line
			(start 0.504 -0.25)
			(end 0.504 0.248)
			(stroke
				(width 0.15)
				(type solid)
			)
			(layer "F.Fab")
		)
		(pad "1" smd roundrect
			(at -0.48 0 270)
			(size 0.59 0.64)
			(layers "F.Cu" "F.Mask" "F.Paste")
			(roundrect_rratio 0.25)
			(net 1 "GND")
			(pintype "passive")
		)
		(pad "2" smd roundrect
			(at 0.48 0 270)
			(size 0.59 0.64)
			(layers "F.Cu" "F.Mask" "F.Paste")
			(roundrect_rratio 0.25)
			(net 3 "VCC1V35")
			(pintype "passive")
		)
	)
	(footprint "antmicro-footprints:C_0402_1005Metric"
		(layer "F.Cu")
		(at 91.774 140.075 -90)
		(descr "Capacitor SMD 0402")
		(tags "capacitor SMD 0402")
		(property "Reference" "C9"
			(at -2.375 -0.326 90)
			(layer "F.SilkS")
			(effects
				(font
					(size 0.7 0.7)
					(thickness 0.15)
				)
				(justify right bottom)
			)
		)
		(property "Value" "C_470n_0402"
			(at 0 1.4 90)
			(layer "F.Fab")
			(effects
				(font
					(size 0.7 0.7)
					(thickness 0.15)
				)
				(justify right bottom)
			)
		)
		(property "Datasheet" "https://product.tdk.com/en/search/capacitor/ceramic/mlcc/info?part_no=C1005X5R1E474M050BB"
			(at 0 0 270)
			(layer "F.Fab")
			(hide yes)
			(effects
				(font
					(size 1.27 1.27)
					(thickness 0.15)
				)
			)
		)
		(property "Description" "SMD Multilayer Ceramic Capacitor, 0.47 µF, 25 V, 0402 [1005 Metric], ± 20%, X5R, C"
			(at 0 0 270)
			(layer "F.Fab")
			(hide yes)
			(effects
				(font
					(size 1.27 1.27)
					(thickness 0.15)
				)
			)
		)
		(property "Author" "Antmicro"
			(at -48.301 231.849 0)
			(layer "F.Fab")
			(hide yes)
			(effects
				(font
					(size 1 1)
					(thickness 0.15)
				)
			)
		)
		(property "Dielectric" ""
			(at -48.301 231.849 0)
			(layer "F.Fab")
			(hide yes)
			(effects
				(font
					(size 1 1)
					(thickness 0.15)
				)
			)
		)
		(property "License" "Apache-2.0"
			(at -48.301 231.849 0)
			(layer "F.Fab")
			(hide yes)
			(effects
				(font
					(size 1 1)
					(thickness 0.15)
				)
			)
		)
		(property "MPN" "C1005X5R1E474M050BB"
			(at -48.301 231.849 0)
			(layer "F.Fab")
			(hide yes)
			(effects
				(font
					(size 1 1)
					(thickness 0.15)
				)
			)
		)
		(property "Manufacturer" "TDK"
			(at -48.301 231.849 0)
			(layer "F.Fab")
			(hide yes)
			(effects
				(font
					(size 1 1)
					(thickness 0.15)
				)
			)
		)
		(property "Val" "470n"
			(at -48.301 231.849 0)
			(layer "F.Fab")
			(hide yes)
			(effects
				(font
					(size 1 1)
					(thickness 0.15)
				)
			)
		)
		(property "Voltage" ""
			(at -48.301 231.849 0)
			(layer "F.Fab")
			(hide yes)
			(effects
				(font
					(size 1 1)
					(thickness 0.15)
				)
			)
		)
		(sheetname "/DDR3/")
		(sheetfile "ddr3.kicad_sch")
		(attr smd)
		(fp_rect
			(start -0.925 -0.47)
			(end 0.925 0.47)
			(stroke
				(width 0.05)
				(type default)
			)
			(fill no)
			(layer "F.CrtYd")
		)
		(fp_line
			(start -0.494 0.248)
			(end -0.494 -0.25)
			(stroke
				(width 0.15)
				(type solid)
			)
			(layer "F.Fab")
		)
		(fp_line
			(start 0.504 0.248)
			(end -0.494 0.248)
			(stroke
				(width 0.15)
				(type solid)
			)
			(layer "F.Fab")
		)
		(fp_line
			(start -0.494 -0.25)
			(end 0.504 -0.25)
			(stroke
				(width 0.15)
				(type solid)
			)
			(layer "F.Fab")
		)
		(fp_line
			(start 0.504 -0.25)
			(end 0.504 0.248)
			(stroke
				(width 0.15)
				(type solid)
			)
			(layer "F.Fab")
		)
		(pad "1" smd roundrect
			(at -0.48 0 270)
			(size 0.59 0.64)
			(layers "F.Cu" "F.Mask" "F.Paste")
			(roundrect_rratio 0.25)
			(net 1 "GND")
			(pintype "passive")
		)
		(pad "2" smd roundrect
			(at 0.48 0 270)
			(size 0.59 0.64)
			(layers "F.Cu" "F.Mask" "F.Paste")
			(roundrect_rratio 0.25)
			(net 3 "VCC1V35")
			(pintype "passive")
		)
	)
)
